%FSTAX23Y23*%
%MOIN*%
%SFA1B1*%

%IPPOS*%
%ADD17C,0.006000*%
%ADD19C,0.008000*%
%ADD21C,0.005000*%
%ADD153C,0.020000*%
%ADD161C,0.075000*%
%ADD168C,0.055000*%
%ADD171C,0.016000*%
%LNgrandmaster-1*%
%LPD*%
G54D17*
X02083Y01411D02*
X02084Y01411D01*
X03407*
X03407Y01411*
G54D19*
X02626Y02716D02*
D01*
X02627Y02716*
X02627Y02716*
X02628Y02716*
X02628Y02716*
X02629Y02717*
X02629Y02717*
X0263Y02717*
X0263Y02717*
X02631Y02718*
X02631Y02718*
X02632Y02718*
X02632Y02718*
X02671Y02754D02*
D01*
X02671Y02754*
X0267Y02754*
X02669Y02754*
X02669Y02754*
X02668Y02754*
X02668Y02754*
X02667Y02753*
X02667Y02753*
X02666Y02753*
X02666Y02753*
X02666Y02752*
X02665Y02752*
X02396Y02718D02*
D01*
X02396Y02718*
X02397Y02718*
X02397Y02717*
X02398Y02717*
X02398Y02717*
X02399Y02717*
X02399Y02716*
X024Y02716*
X024Y02716*
X02401Y02716*
X02401Y02716*
X02401Y02716*
X02671Y02754D02*
X03089D01*
X02401Y02716D02*
X02626D01*
X02671Y02754D02*
X02671D01*
X02632Y02718D02*
X02665Y02752D01*
X02394Y0272D02*
X02396Y02718D01*
X02494Y02661D02*
X04114D01*
X0233Y02215D02*
X05577D01*
X01393Y01816D02*
X01517Y01941D01*
X02384*
X01399Y03522D02*
X014Y03523D01*
X01408Y03979D02*
Y0398D01*
X014Y03971D02*
X01408Y03979D01*
X014Y03523D02*
Y03971D01*
X01399Y03075D02*
Y03522D01*
X04605Y02997D02*
X04794Y02808D01*
X03276Y02964D02*
X03277Y02963D01*
X03276Y02964D02*
Y02983D01*
X03275Y02984D02*
X03276Y02983D01*
X03275Y02984D02*
Y03019D01*
X03331Y03075*
Y03153*
X03297Y03187D02*
X03331Y03153D01*
X0321Y03135D02*
X03262Y03187D01*
X03297*
X03183Y03135D02*
X0321D01*
X03232Y03187D02*
X0326Y03215D01*
X03468*
X03188Y03187D02*
X03232D01*
X01798Y01304D02*
X0181Y01316D01*
X02189Y01281D02*
X02206Y01298D01*
X01572Y01281D02*
X02189D01*
X01567Y01285D02*
X01572Y01281D01*
X0406Y03155D02*
D01*
X03854Y03151D02*
X03857D01*
X03861Y03155*
X0406*
X04012Y03115D02*
D01*
X03939Y03121D02*
X03942D01*
X03948Y03115*
X04012*
X06296D01*
X03277Y02963D02*
X03351Y02889D01*
X03369*
X0337Y02888*
X03232Y03098D02*
X03275Y03141D01*
X03089Y02754D02*
X03232Y02897D01*
Y03098*
X03097Y0297D02*
X03197D01*
X03096Y02969D02*
X03097Y0297D01*
X02577Y02969D02*
X03096D01*
X03653Y03293D02*
X03655Y03294D01*
X03661*
X03662Y03296*
X06433*
X03394Y03447D02*
X03441Y034D01*
X04926D02*
X04927Y03401D01*
X03441Y034D02*
X04926D01*
X04927Y03401D02*
X0644D01*
X05049Y03264D02*
X0505Y03266D01*
X03744Y03261D02*
X03747D01*
X0375Y03264*
X05049*
X03687Y02997D02*
X04605D01*
X03468Y03215D02*
X03687Y02997D01*
X02997Y03235D02*
X0323D01*
X02362Y02696D02*
X02494D01*
X02509Y02681*
X02217Y0284D02*
X02362Y02696D01*
X01399Y03075D02*
X01634Y0284D01*
X02217*
X01879Y01811D02*
X03056D01*
X02635Y0179D02*
X02646Y01779D01*
X02579Y0179D02*
X02635D01*
X02385Y032D02*
X02411Y03174D01*
X01459Y03147D02*
X02435D01*
X02205Y032D02*
X02385D01*
X02435Y03147D02*
X0246Y03172D01*
X02405Y03261D02*
X02411Y03266D01*
X02259Y03261D02*
X02405D01*
X03366Y0327D02*
X03367Y03271D01*
X03373D02*
X03374Y03273D01*
X03367Y03271D02*
X03373D01*
X02591Y03186D02*
X02591D01*
X02577Y032D02*
X02591Y03186D01*
X02454Y032D02*
X02577D01*
X02598Y03293D02*
X03252D01*
X0259Y03288D02*
X02593D01*
X02598Y03293*
X03252D02*
X03263Y03303D01*
X0086Y01322D02*
X00996Y01187D01*
X0086Y01322D02*
Y02098D01*
X00997Y02236*
X00996Y02256D02*
X01732D01*
X01739Y02249*
X02499Y02236D02*
X02499Y02236D01*
X02472Y02249D02*
X02494Y0227D01*
X01739Y02249D02*
X02472D01*
X00997Y02236D02*
X02499D01*
X01187Y02314D02*
X02409D01*
X0102Y02481D02*
X01187Y02314D01*
X0181Y01316D02*
X02013D01*
X02016Y01319*
X02004Y01336D02*
X03379D01*
X02028Y01361D02*
X02029Y01361D01*
X02016Y01319D02*
X02499D01*
X00988Y01717D02*
X02588D01*
X02604Y01734*
X02494Y0227D02*
X02529D01*
X02549Y0225D02*
X02608D01*
X02529Y0227D02*
X02549Y0225D01*
X02644Y02272D02*
X02645Y02274D01*
X02629Y02272D02*
X02644D01*
X02608Y0225D02*
X02629Y02272D01*
X02418Y03118D02*
X02428D01*
X02416Y03199D02*
X02429Y03212D01*
X02438*
X0246Y03235*
X02414Y03199D02*
X02416D01*
X0246Y03172D02*
X02462D01*
X02428Y03118D02*
X02577Y02969D01*
X01904Y04017D02*
X02353D01*
X01903Y04018D02*
X01904Y04017D01*
X02002Y04152D02*
X02043D01*
X01965Y04156D02*
X02018Y04209D01*
X02067D02*
X02121Y04156D01*
X02018Y04209D02*
X02067D01*
X02121Y04156D02*
X0397D01*
X0401Y04115*
X01779Y04156D02*
X01965D01*
X02693Y03266D02*
X027Y03273D01*
X02411Y03266D02*
X02693D01*
X02974Y03257D02*
X02997Y03235D01*
X02428Y03174D02*
X02454Y032D01*
X02429Y02621D02*
X02958D01*
X02923Y02481D02*
X02948Y02456D01*
X027Y03273D02*
X03374D01*
X01605Y04136D02*
X01986D01*
X01569Y04171D02*
X01605Y04136D01*
X01986D02*
X02002Y04152D01*
X01769Y00807D02*
X01868Y00906D01*
X01395Y00807D02*
X01769D01*
X01296Y00906D02*
X01395Y00807D01*
X01868Y00906D02*
X02452D01*
X01004D02*
X01296D01*
X03507Y04088D02*
X05267D01*
X03504Y04086D02*
X03507Y04088D01*
X03958Y01512D02*
X03989Y01543D01*
Y01543*
X03994Y01548*
Y01551*
X03897Y01512D02*
X03958D01*
X03963Y01552D02*
X03969D01*
X03951Y01564D02*
X03963Y01552D01*
X0393Y01564D02*
X03951D01*
X01822Y01674D02*
X01882D01*
X01883Y01675*
X02694Y01481D02*
X03543D01*
X03584Y0144*
X03993*
X04064Y01511*
X02384Y01941D02*
X03332D01*
X03357Y01916*
X03569*
X03588Y01897*
X03747*
X03804Y0184*
X0505Y03266D02*
X06334D01*
X02499Y02236D02*
X05634D01*
X02629Y0177D02*
X02633Y01766D01*
X02626Y0177D02*
X02629D01*
X02633Y01766D02*
X03475D01*
X03493Y01784*
X03703*
X03709Y0179*
X03993*
X03999Y01796*
X04064*
X06296Y03115D02*
X06302Y03121D01*
X06304*
X04114Y02661D02*
X0418Y02595D01*
X04132Y01751D02*
X04134D01*
X04116Y01735D02*
X04132Y01751D01*
X03579Y01735D02*
X04116D01*
X03578Y01734D02*
X03579Y01735D01*
X02604Y01734D02*
X03578D01*
X02299Y01916D02*
X03334D01*
X0335Y019*
X03444*
X03453Y01891*
X03554*
X02509Y02681D02*
X04212D01*
X04298Y02595*
X02646Y01779D02*
X03465D01*
X03486Y018*
X03635*
X03651Y01816*
X03944*
X0258Y02412D02*
X02586Y02406D01*
X02575Y02412D02*
X0258D01*
X02586Y02406D02*
X04039D01*
X03499Y01766D02*
X03719D01*
X03483Y0175D02*
X03499Y01766D01*
X02617Y0175D02*
X03483D01*
X02612Y01755D02*
X02617Y0175D01*
X02549Y01755D02*
X02612D01*
X06278Y03226D02*
X06282D01*
X06269Y03235D02*
X06278Y03226D01*
X03806Y03235D02*
X06269D01*
X02423Y03557D02*
X02434Y03546D01*
X0144Y03557D02*
X02423D01*
X03604Y02606D02*
X03623Y02587D01*
X03571Y02606D02*
X03604D01*
X03566Y02601D02*
X03571Y02606D01*
X02821Y02601D02*
X03566D01*
X06342Y03319D02*
X06354Y03331D01*
X03542Y03319D02*
X06342D01*
X03302Y03344D02*
X03612D01*
X03639Y03371D02*
X06409D01*
X03612Y03344D02*
X03639Y03371D01*
X03457Y03436D02*
X06469D01*
X03436Y03457D02*
X03457Y03436D01*
X06469D02*
X06479Y03426D01*
X038Y032D02*
X06308D01*
X03431Y01682D02*
X03599D01*
X03429Y0168D02*
X03431Y01682D01*
X03202Y01673D02*
X03211Y01681D01*
X03204Y01693D02*
X03205Y01694D01*
X03599Y01682D02*
X03606Y01675D01*
X03419Y01693D02*
X03436Y01711D01*
X01893Y01693D02*
X03204D01*
X03606Y01675D02*
X03724D01*
X01885Y01673D02*
X03202D01*
X01883Y01675D02*
X01885Y01673D01*
X03205Y01694D02*
X03312D01*
X03312Y01693*
X03419*
X03307Y0168D02*
X03429D01*
X03306Y01681D02*
X03307Y0168D01*
X03211Y01681D02*
X03306D01*
X03436Y01711D02*
X03589D01*
X02667Y01641D02*
X03782D01*
X03792Y01651*
X03082Y01591D02*
X03091Y016D01*
X03699D02*
X03705Y01606D01*
X03091Y016D02*
X03699D01*
X06445Y03396D02*
X06447D01*
X0644Y03401D02*
X06445Y03396D01*
X02478Y00932D02*
Y00937D01*
X02452Y00906D02*
X02478Y00932D01*
X02719Y01591D02*
X03082D01*
X02919Y01536D02*
X03873D01*
X03897Y01512*
X06333Y03155D02*
X06337Y03151D01*
X0406Y03155D02*
X06333D01*
X06337Y03151D02*
X06339D01*
X02702Y03257D02*
X02974D01*
X0246Y03235D02*
X0268D01*
X02702Y03257*
X02666Y0164D02*
X02667Y01641D01*
X02411Y03174D02*
X02428D01*
X01008Y0143D02*
X0101D01*
X02274Y01506D02*
X03544D01*
X01017Y01437D02*
X02446D01*
X0101Y0143D02*
X01017Y01437D01*
X02059Y01386D02*
X03379D01*
X03402Y01361D02*
X03404Y01363D01*
X02029Y01361D02*
X03402D01*
X02499Y01319D02*
X02502Y01316D01*
X02525Y02463D02*
X02598D01*
X02616Y02481D02*
X02923D01*
X02598Y02463D02*
X02616Y02481D01*
X02841Y02263D02*
X03342D01*
X02803Y02307D02*
X02837Y02341D01*
X03498*
X01009Y01956D02*
X0102Y01967D01*
X02409*
X02643Y01616D02*
X03469D01*
X02557Y03616D02*
X02799D01*
X02129Y03587D02*
X02257D01*
X023Y03629*
X02543*
X02557Y03616*
X02123Y03571D02*
X02611D01*
X02636Y03596*
X01754Y03661D02*
X01755Y03661D01*
X02679*
X02679Y03661*
X01549Y03621D02*
X0187D01*
X01895Y03645*
X02652*
X02115Y03601D02*
X02129Y03587D01*
X01593Y03577D02*
X02117D01*
X02652Y03645D02*
X02661Y03636D01*
X03424*
X01884Y03601D02*
X02115D01*
X02117Y03577D02*
X02123Y03571D01*
X02636Y03596D02*
X03239D01*
X01574D02*
X01593Y03577D01*
X02525Y03506D02*
X02569Y03462D01*
X03037D02*
X03056Y03481D01*
X03529*
X02569Y03462D02*
X03037D01*
X02234Y03506D02*
X02525D01*
X02993Y03751D02*
X03699D01*
X03019Y03836D02*
X03699D01*
X03014Y03831D02*
X03019Y03836D01*
X03014Y03831D02*
Y03831D01*
X02894Y01561D02*
X03327D01*
X03336Y01552D02*
X03769D01*
X03327Y01561D02*
X03336Y01552D01*
X03769D02*
X03807Y0159D01*
X03904D02*
X0393Y01564D01*
X03807Y0159D02*
X03904D01*
X03959Y01599D02*
X04178D01*
X03952Y01606D02*
X03959Y01599D01*
X03705Y01606D02*
X03952D01*
X03544Y01506D02*
X03594Y01456D01*
X03922*
X03939Y01473*
X03961D02*
X04034Y01546D01*
X03939Y01473D02*
X03961D01*
X04178Y01599D02*
X04179Y01601D01*
X03469Y01616D02*
X03477Y01623D01*
X04151*
X03792Y01651D02*
X04134D01*
X03799Y03201D02*
X038Y032D01*
X06308D02*
X06309Y03199D01*
X0401Y04115D02*
X04754D01*
X03829Y03176D02*
X06274D01*
X06275Y03175*
X06377Y03191D02*
X06439D01*
X06361Y03175D02*
X06377Y03191D01*
X06275Y03175D02*
X06361D01*
X06433Y03296D02*
X06438Y03291D01*
X06444*
X03469Y03456D02*
X06509D01*
G54D21*
X02589Y00324D02*
D01*
X02589Y00325*
X02589Y00325*
X02589Y00325*
X02589Y00326*
X0259Y00326*
X0259Y00326*
X0259Y00327*
X0259Y00327*
X02583Y00303D02*
D01*
X02583Y00304*
X02583Y00304*
X02583Y00304*
X02583Y00305*
X02584Y00305*
X02584Y00305*
X02577Y00297D02*
D01*
X02575Y00297*
X02574Y00297*
X02573Y00297*
X02572Y00296*
X02571Y00296*
X02569Y00295*
X02568Y00295*
X02567Y00294*
X02566Y00293*
X02565Y00292*
X02564Y00291*
X02564Y0029*
X02563Y00289*
X02562Y00288*
X02562Y00287*
X02561Y00286*
X02561Y00285*
X0256Y00283*
X0256Y00282*
X0256Y00281*
X0256Y00279*
X0256Y00278*
X0256Y00277*
X0256Y00276*
X0256Y00274*
X02561Y00273*
X02561Y00272*
X02562Y00271*
X02562Y0027*
X02563Y00269*
X02564Y00267*
X02565Y00266*
X02566Y00266*
X02567Y00265*
X02568Y00264*
X02569Y00263*
X0257Y00263*
X02571Y00262*
X02572Y00262*
X02573Y00261*
X02575Y00261*
X02576Y00261*
X02577Y00261*
X02578Y00261*
X0258Y00261*
X02581Y00261*
X02582Y00261*
X02584Y00261*
X02585Y00262*
X02586Y00262*
X02587Y00263*
X02588Y00263*
X02589Y00264*
X0259Y00265*
X02591Y00266*
X02592Y00267*
X02593Y00268*
X02594Y00269*
X02594Y0027*
X02595Y00271*
X02595Y00272*
X02596Y00274*
X02596Y00275*
X02583Y00303D02*
D01*
X02581Y00301*
X02581Y003*
X026Y00278D02*
D01*
X02599Y00278*
X02599Y00278*
X02599Y00278*
X02598Y00278*
X02598Y00277*
X02598Y00277*
X02598Y00277*
X02597Y00277*
X02597Y00276*
X02597Y00276*
X02597Y00276*
X02597Y00276*
X02596Y00275*
X02596Y00275*
X02596Y00275*
X02577Y00297D02*
D01*
X02577Y00298*
X02577Y00298*
X02578Y00298*
X02578Y00298*
X02578Y00298*
X02579Y00298*
X02579Y00298*
X02579Y00298*
X0258Y00299*
X0258Y00299*
X0258Y00299*
X0258Y00299*
X0258Y003*
X02581Y003*
X02589Y00324D02*
D01*
X02588Y00323*
X02588Y00322*
X02588Y00321*
X02587Y0032*
X02604Y00279D02*
D01*
X02603Y00279*
X02602Y00279*
X02601Y00279*
X026Y00278*
X026Y00278*
X02578Y00279D02*
D01*
X02582Y00283*
X02586Y00288*
X02589Y00292*
X02591Y00295*
X02602Y00376D02*
D01*
X02602Y00376*
X02602Y00375*
X02602Y00374*
X02602Y00374*
X02602Y00373*
X02603Y00373*
X02603Y00373*
X02603Y00372*
X02603Y00372*
X02604Y00371*
X02604Y00371*
X02604Y0037*
X02605Y0037*
X02605Y0037*
X02606Y0037*
X02606Y00369*
X02607Y00369*
X02607Y00369*
X02608Y00369*
X02608Y00369*
X02609Y00369*
X02609Y00369*
X02609Y00369*
X02616Y00354D02*
D01*
X02616Y00354*
X02617Y00354*
X02617Y00354*
X02618Y00354*
X02618Y00354*
X02619Y00354*
X02619Y00354*
X0262Y00355*
X0262Y00355*
X0262Y00355*
X02621Y00356*
X02621Y00356*
X02622Y00356*
X02622Y00357*
X02622Y00357*
X02622Y00358*
X02623Y00358*
X02623Y00359*
X02623Y00359*
X02623Y0036*
X02623Y0036*
X02623Y00361*
Y00361*
X02623Y00362*
X02623Y00362*
X02623Y00363*
X02623Y00363*
X02623Y00364*
X02622Y00364*
X02622Y00365*
X02622Y00365*
X02622Y00366*
X02621Y00366*
X02621Y00366*
X0262Y00367*
X0262Y00367*
X0262Y00367*
X02619Y00368*
X02619Y00368*
X02618Y00368*
X02618Y00368*
X02617Y00368*
X02617Y00368*
X02616Y00369*
X02616Y00369*
X02607Y00354D02*
D01*
X02607Y00354*
X02606Y00353*
X02606Y00353*
X02605Y00353*
X02604Y00353*
X02604Y00353*
X02604Y00353*
X02603Y00352*
X02603Y00352*
X02602Y00352*
X02602Y00351*
X02601Y00351*
X02601Y00351*
X02601Y0035*
X02601Y0035*
X026Y00349*
X026Y00349*
X026Y00348*
X026Y00348*
X026Y00347*
X026Y00347*
X026Y00346*
Y00346*
X026Y00345*
X026Y00345*
X026Y00344*
X026Y00344*
X026Y00343*
X026Y00343*
X02601Y00342*
X02601Y00342*
X02601Y00341*
X02601Y00341*
X02602Y00341*
X02602Y0034*
X02603Y0034*
X02603Y0034*
X02604Y00339*
X02604Y00339*
X02604Y00339*
X02605Y00339*
X02606Y00339*
X02606Y00339*
X02607Y00339*
X02607Y00339*
X02619Y00324D02*
D01*
X0262Y00324*
X0262Y00324*
X02621Y00324*
X02621Y00324*
X02622Y00324*
X02622Y00324*
X02623Y00324*
X02623Y00325*
X02624Y00325*
X02624Y00325*
X02624Y00326*
X02625Y00326*
X02625Y00326*
X02625Y00327*
X02626Y00327*
X02626Y00328*
X02626Y00328*
X02626Y00329*
X02627Y00329*
X02627Y0033*
X02627Y0033*
X02627Y00331*
Y00331*
X02627Y00332*
X02627Y00332*
X02627Y00333*
X02626Y00333*
X02626Y00334*
X02626Y00334*
X02626Y00335*
X02625Y00335*
X02625Y00336*
X02625Y00336*
X02624Y00336*
X02624Y00337*
X02624Y00337*
X02623Y00337*
X02623Y00338*
X02622Y00338*
X02622Y00338*
X02621Y00338*
X02621Y00338*
X0262Y00338*
X0262Y00339*
X02619Y00339*
X02604Y00324D02*
D01*
X02604Y00324*
X02603Y00323*
X02603Y00323*
X02602Y00323*
X02602Y00323*
X02601Y00323*
X02601Y00323*
X026Y00322*
X026Y00322*
X026Y00322*
X02599Y00321*
X02599Y00321*
X02598Y00321*
X02598Y0032*
X02598Y0032*
X02598Y00319*
X02597Y00319*
X02597Y00318*
X02597Y00318*
X02591Y00295D02*
D01*
X02591Y00295*
X02591Y00296*
X02591Y00296*
X02592Y00297*
X02592Y00297*
X02608Y00457D02*
D01*
X02604Y0045*
X026Y00444*
X02597Y00437*
X02595Y0043*
X02593Y00422*
X02591Y00415*
X0259Y00408*
X0259Y00404*
D01*
X0259Y00404*
X0259Y00404*
X02633Y00472D02*
D01*
X02628Y00467*
X02623Y00461*
X02619Y00455*
X02615Y00448*
X02612Y00442*
X02609Y00435*
X02607Y00428*
X02605Y0042*
X02603Y00413*
X02602Y00406*
X02602Y00398*
X02602Y00396*
X02625Y0048D02*
D01*
X0262Y00474*
X02616Y00469*
X02612Y00463*
X02608Y00457*
X02909Y00366D02*
D01*
X02909Y00366*
X02909Y00365*
X02909Y00365*
X02909Y00364*
X02909Y00364*
X02909Y00363*
X02909Y00363*
X0291Y00362*
X0291Y00362*
X0291Y00362*
X02911Y00361*
X02911Y00361*
X02912Y00361*
X02912Y0036*
X02912Y0036*
X02913Y0036*
X02913Y00359*
X02914Y00359*
X02914Y00359*
X02915Y00359*
X02915Y00359*
X02916Y00359*
X02916Y00359*
Y00344D02*
D01*
X02917Y00344*
X02917Y00344*
X02918Y00344*
X02918Y00344*
X02919Y00344*
X02919Y00345*
X0292Y00345*
X0292Y00345*
X02921Y00345*
X02921Y00346*
X02921Y00346*
X02922Y00346*
X02922Y00347*
X02922Y00347*
X02923Y00348*
X02923Y00348*
X02923Y00349*
X02923Y00349*
X02923Y0035*
X02924Y0035*
X02924Y00351*
X02924Y00351*
Y00352*
X02924Y00352*
X02924Y00353*
X02923Y00353*
X02923Y00354*
X02923Y00354*
X02923Y00355*
X02923Y00355*
X02922Y00356*
X02922Y00356*
X02922Y00356*
X02921Y00357*
X02921Y00357*
X02921Y00358*
X0292Y00358*
X0292Y00358*
X02919Y00358*
X02919Y00358*
X02918Y00359*
X02918Y00359*
X02917Y00359*
X02917Y00359*
X02916Y00359*
X02903Y00344D02*
D01*
X02902Y00344*
X02902Y00344*
X02901Y00344*
X02901Y00344*
X029Y00343*
X029Y00343*
X02899Y00343*
X02899Y00343*
X02898Y00343*
X02898Y00342*
X02898Y00342*
X02897Y00341*
X02897Y00341*
X02897Y00341*
X02896Y0034*
X02896Y0034*
X02896Y00339*
X02896Y00339*
X02896Y00338*
X02895Y00338*
X02895Y00337*
X02895Y00337*
Y00336*
X02895Y00336*
X02895Y00335*
X02896Y00335*
X02896Y00334*
X02896Y00334*
X02896Y00333*
X02896Y00333*
X02897Y00332*
X02897Y00332*
X02897Y00331*
X02898Y00331*
X02898Y00331*
X02898Y0033*
X02899Y0033*
X02899Y0033*
X029Y0033*
X029Y00329*
X02901Y00329*
X02901Y00329*
X02902Y00329*
X02902Y00329*
X02903Y00329*
X02915Y00314D02*
D01*
X02915Y00314*
X02916Y00314*
X02916Y00314*
X02917Y00314*
X02917Y00314*
X02918Y00315*
X02918Y00315*
X02918Y00315*
X02919Y00315*
X02919Y00316*
X0292Y00316*
X0292Y00316*
X0292Y00317*
X02921Y00317*
X02921Y00318*
X02921Y00318*
X02921Y00319*
X02922Y00319*
X02922Y0032*
X02922Y0032*
X02922Y00321*
X02922Y00321*
Y00322*
X02922Y00322*
X02922Y00323*
X02922Y00323*
X02922Y00324*
X02921Y00324*
X02921Y00325*
X02921Y00325*
X02921Y00326*
X0292Y00326*
X0292Y00326*
X0292Y00327*
X02919Y00327*
X02919Y00328*
X02918Y00328*
X02918Y00328*
X02918Y00328*
X02917Y00328*
X02917Y00329*
X02916Y00329*
X02916Y00329*
X02915Y00329*
X02915Y00329*
X02905Y00314D02*
D01*
X02904Y00314*
X02904Y00314*
X02903Y00314*
X02903Y00314*
X02902Y00313*
X02902Y00313*
X02901Y00313*
X02901Y00313*
X029Y00313*
X029Y00312*
X02899Y00312*
X02899Y00311*
X02899Y00311*
X02898Y00311*
X02898Y0031*
X02898Y0031*
X02898Y00309*
X02898Y00309*
X02897Y00308*
X02897Y00308*
X02897Y00307*
X02897Y00307*
X02897Y00306*
X02926Y004D02*
D01*
X02927Y00401*
X02927Y00401*
X02927Y00401*
X02927Y00402*
X02927Y00402*
X02927Y00402*
X02928Y00403*
X02928Y00403*
X02928Y00403*
X02928Y00404*
X02928Y00404*
X02928Y00404*
X02885Y00274D02*
D01*
X02886Y00273*
X02886Y00272*
X02887Y00271*
X02888Y00269*
X02888Y00268*
X02889Y00267*
X0289Y00266*
X02891Y00265*
X02892Y00264*
X02893Y00263*
X02894Y00263*
X02895Y00262*
X02896Y00261*
X02898Y00261*
X02899Y00261*
X029Y0026*
X02902Y0026*
X02903Y0026*
X02904Y0026*
X02906Y0026*
X02907Y0026*
X02908Y0026*
X0291Y00261*
X02911Y00261*
X02912Y00262*
X02913Y00262*
X02915Y00263*
X02916Y00264*
X02917Y00264*
X02918Y00265*
X02919Y00266*
X02919Y00267*
X0292Y00268*
X02921Y0027*
X02922Y00271*
X02922Y00272*
X02923Y00273*
X02923Y00275*
X02923Y00275*
X02911Y004D02*
D01*
X02911Y004*
X02911Y004*
X02911Y00401*
X02912Y00401*
X02912Y00401*
X02912Y00401*
X02912Y00402*
X02911Y004D02*
D01*
X02907Y00397*
X02904Y00395*
X02901Y00392*
X02899Y00389*
X02896Y00386*
X02894Y00382*
X02892Y00379*
X0289Y00375*
X02889Y00372*
X02888Y00368*
X02887Y00364*
X02886Y0036*
X02885Y00356*
X02885Y00352*
X02912Y00402D02*
D01*
X02913Y00404*
X02914Y00406*
X02915Y00408*
X02916Y0041*
X02916Y00413*
X02917Y00415*
X02917Y00418*
X02917Y00419*
X02928Y00834D02*
D01*
X02928Y00835*
X02928Y00836*
X02928Y00836*
X02927Y00837*
X02927Y00838*
X02927Y00839*
X02927Y00839*
X02926Y0084*
X02926Y00841*
X02925Y00841*
X02925Y00842*
X02925Y00842*
X02897Y00289D02*
D01*
X02897Y00289*
X02897Y00288*
X02897Y00288*
X02897Y00288*
X02897Y00287*
X02898Y00287*
X02898Y00287*
X02898Y00286*
X02898Y00286*
X02898Y00286*
X02899Y00285*
X02899Y00285*
X02759Y0094D02*
D01*
X02759Y00938*
X02759Y00935*
X0276Y00933*
X0276Y0093*
X02761Y00928*
X02762Y00925*
X02763Y00923*
X02765Y00921*
X02766Y00919*
X02768Y00917*
X02769Y00915*
X0277Y00914*
X02767Y00976D02*
D01*
X02766Y00974*
X02765Y00973*
X02764Y00971*
X02762Y00969*
X02762Y00968*
X02761Y00966*
X0276Y00964*
X0276Y00962*
X02759Y0096*
X02759Y00958*
X02759Y00956*
X02759Y00956*
X02915Y00852D02*
D01*
X02912Y00854*
X0291Y00856*
X02907Y00858*
X02904Y0086*
X02901Y00861*
X02898Y00863*
X02895Y00864*
X02892Y00864*
X02889Y00865*
X02886Y00865*
X02882Y00866*
X02881Y00866*
X02789Y00895D02*
D01*
X02794Y0089*
X028Y00886*
X02805Y00882*
X02811Y00878*
X02818Y00875*
X02824Y00872*
X02831Y0087*
X02837Y00868*
X02844Y00867*
X02851Y00866*
X02858Y00866*
X0286Y00866*
X02748Y00285D02*
D01*
X02748Y00284*
X02748Y00284*
X02748Y00283*
X02748Y00283*
X02748Y00283*
X02748Y00282*
X02748Y00282*
X02748Y00282*
X02748Y00282*
X02737Y00267D02*
D01*
X02738Y00266*
X02739Y00265*
X0274Y00265*
X02741Y00264*
X02742Y00263*
X02743Y00263*
X02744Y00263*
X02745Y00262*
X02746Y00262*
X02747Y00262*
X02749Y00262*
X0275Y00262*
X02751Y00262*
X02752Y00262*
X02753Y00262*
X02754Y00263*
X02755Y00263*
X02757Y00264*
X02758Y00264*
X02759Y00265*
X0276Y00265*
X0276Y00266*
X02761Y00267*
X02762Y00268*
X02763Y00269*
X02763Y0027*
X02764Y00271*
X02765Y00272*
X02765Y00273*
X02765Y00274*
X02766Y00275*
X02737Y00387D02*
D01*
X02733Y00383*
X0273Y00378*
X02726Y00373*
X02723Y00368*
X0272Y00363*
X02718Y00357*
X02716Y00352*
X02715Y00346*
X02714Y0034*
X02713Y00334*
X02713Y00329*
X02713Y00327*
D01*
X02713Y00321*
X02713Y00315*
X02714Y00309*
X02716Y00303*
X02718Y00297*
X0272Y00292*
X02723Y00286*
X02726Y00281*
X02729Y00276*
X02733Y00271*
X02737Y00267*
X02737Y00267*
X0274Y00348D02*
D01*
X02741Y00348*
X02741Y00348*
X02742Y00348*
X02742Y00348*
X02743Y00348*
X02743Y00348*
X02744Y00348*
X02744Y00349*
X02744Y00349*
X02745Y00349*
X02745Y0035*
X02746Y0035*
X02746Y00351*
X02746Y00351*
X02747Y00351*
X02747Y00352*
X02747Y00352*
X02747Y00353*
X02747Y00353*
X02747Y00354*
X02748Y00354*
X02748Y00355*
X02748Y00355*
X02733Y00348D02*
D01*
X02733Y00348*
X02732Y00348*
X02732Y00347*
X02731Y00347*
X02731Y00347*
X0273Y00347*
X0273Y00347*
X02729Y00346*
X02729Y00346*
X02729Y00346*
X02728Y00346*
X02728Y00345*
X02728Y00345*
X02727Y00344*
X02727Y00344*
X02727Y00343*
X02726Y00343*
X02726Y00342*
X02726Y00342*
X02726Y00341*
X02726Y00341*
X02726Y0034*
Y0034*
X02726Y00339*
X02726Y00339*
X02726Y00338*
X02726Y00338*
X02726Y00337*
X02727Y00337*
X02727Y00336*
X02727Y00336*
X02728Y00336*
X02728Y00335*
X02728Y00335*
X02729Y00334*
X02729Y00334*
X02729Y00334*
X0273Y00333*
X0273Y00333*
X02731Y00333*
X02731Y00333*
X02732Y00333*
X02732Y00333*
X02733Y00333*
X02733Y00333*
X0275Y00318D02*
D01*
X02751Y00318*
X02751Y00318*
X02752Y00318*
X02752Y00318*
X02753Y00318*
X02753Y00318*
X02754Y00318*
X02754Y00319*
X02754Y00319*
X02755Y00319*
X02755Y0032*
X02756Y0032*
X02756Y00321*
X02756Y00321*
X02757Y00321*
X02757Y00322*
X02757Y00322*
X02757Y00323*
X02757Y00323*
X02757Y00324*
X02758Y00324*
X02758Y00325*
Y00325*
X02758Y00326*
X02757Y00326*
X02757Y00327*
X02757Y00327*
X02757Y00328*
X02757Y00328*
X02757Y00329*
X02756Y00329*
X02756Y0033*
X02756Y0033*
X02755Y00331*
X02755Y00331*
X02754Y00331*
X02754Y00331*
X02754Y00332*
X02753Y00332*
X02753Y00332*
X02752Y00332*
X02752Y00332*
X02751Y00333*
X02751Y00333*
X0275Y00333*
X02733Y00318D02*
D01*
X02733Y00318*
X02732Y00318*
X02732Y00317*
X02731Y00317*
X02731Y00317*
X0273Y00317*
X0273Y00317*
X02729Y00316*
X02729Y00316*
X02729Y00316*
X02728Y00316*
X02728Y00315*
X02728Y00315*
X02727Y00314*
X02727Y00314*
X02727Y00313*
X02726Y00313*
X02726Y00312*
X02726Y00312*
X02726Y00311*
X02726Y00311*
X02726Y0031*
Y0031*
X02726Y00309*
X02726Y00309*
X02726Y00308*
X02726Y00308*
X02726Y00307*
X02727Y00307*
X02727Y00306*
X02727Y00306*
X02728Y00306*
X02728Y00305*
X02728Y00305*
X02729Y00304*
X02729Y00304*
X02729Y00304*
X0273Y00303*
X0273Y00303*
X02731Y00303*
X02731Y00303*
X02732Y00303*
X02732Y00303*
X02733Y00303*
X02733Y00303*
X02748Y00295D02*
D01*
X02748Y00296*
X02747Y00296*
X02747Y00297*
X02747Y00297*
X02747Y00298*
X02747Y00298*
X02747Y00299*
X02746Y00299*
X02746Y003*
X02746Y003*
X02745Y003*
X02745Y00301*
X02745Y00301*
X02744Y00301*
X02744Y00302*
X02743Y00302*
X02743Y00302*
X02742Y00302*
X02742Y00302*
X02741Y00302*
X02741Y00303*
X0274Y00303*
X0274Y00303*
X02749Y00383D02*
D01*
X02749Y00383*
X02749Y00383*
X02748Y00382*
X02748Y00382*
X02748Y00382*
X02748Y00381*
X02748Y00381*
X02748Y00381*
X02748Y0038*
X02748Y0038*
X02748Y0038*
X02748Y0038*
X02515Y0036D02*
D01*
X02515Y0036*
X02516Y00359*
X02516Y00359*
X02517Y00359*
X02517Y00359*
X02518Y00358*
X02518Y00358*
X02519Y00358*
X02519Y00358*
X0252Y00358*
X0252Y00358*
X02521Y00358*
X02521Y00358*
X02522Y00358*
X02522Y00358*
X02523Y00358*
X02523Y00359*
X02524Y00359*
X02524Y00359*
X02525Y00359*
X02525Y0036*
X02525Y0036*
X02526Y0036*
X02515D02*
D01*
X02515Y00361*
X02514Y00361*
X02514Y00361*
X02513Y00361*
X02513Y00362*
X02512Y00362*
X02512Y00362*
X02511Y00362*
X02511Y00362*
X0251Y00362*
X0251Y00362*
X02509Y00362*
X02509Y00362*
X02508Y00362*
X02508Y00362*
X02507Y00362*
X02507Y00362*
X02506Y00362*
X02506Y00361*
X02505Y00361*
X02505Y00361*
X02505Y0036*
X02504Y0036*
D01*
X02504Y0036*
X02504Y00359*
X02503Y00359*
X02503Y00359*
X02503Y00358*
X02503Y00358*
X02502Y00357*
X02502Y00357*
X02502Y00356*
X02502Y00356*
X02502Y00355*
X02502Y00354*
X02502Y00354*
X02502Y00353*
X02502Y00353*
X02503Y00352*
X02503Y00352*
X02503Y00351*
X02503Y00351*
X02503Y00351*
X02504Y0035*
X02504Y0035*
X02504Y0035*
Y00339D02*
D01*
X02505Y00339*
X02505Y0034*
X02505Y0034*
X02506Y00341*
X02506Y00341*
X02506Y00342*
X02506Y00342*
X02506Y00343*
X02506Y00343*
X02506Y00344*
X02507Y00344*
X02507Y00345*
X02506Y00345*
X02506Y00346*
X02506Y00346*
X02506Y00347*
X02506Y00347*
X02506Y00348*
X02505Y00348*
X02505Y00349*
X02505Y00349*
X02505Y00349*
X02504Y0035*
X02494Y00339D02*
D01*
X02494Y00339*
X02495Y00338*
X02495Y00338*
X02495Y00338*
X02496Y00337*
X02496Y00337*
X02497Y00337*
X02497Y00337*
X02498Y00337*
X02498Y00337*
X02499Y00337*
X02499Y00337*
X025Y00337*
X025Y00337*
X02501Y00337*
X02501Y00337*
X02502Y00337*
X02502Y00338*
X02503Y00338*
X02503Y00338*
X02504Y00338*
X02504Y00339*
X02504Y00339*
X02491Y00341D02*
D01*
X02491Y00342*
X0249Y00342*
X0249Y00342*
X0249Y00343*
X02489Y00343*
X02489Y00343*
X02488Y00343*
X02488Y00343*
X02487Y00344*
X02487Y00344*
X02486Y00344*
X02486Y00344*
X02485Y00344*
X02485Y00343*
X02484Y00343*
X02484Y00343*
X02483Y00343*
X02483Y00343*
X02482Y00343*
X02482Y00342*
X02481Y00342*
X02481Y00342*
X02481Y00341*
D01*
X0248Y00341*
X0248Y00341*
X0248Y0034*
X02479Y0034*
X02479Y00339*
X02479Y00339*
X02479Y00338*
X02479Y00338*
X02479Y00337*
X02478Y00337*
X02478Y00336*
X02478Y00336*
X02479Y00335*
X02479Y00335*
X02479Y00334*
X02479Y00334*
X02479Y00333*
X02479Y00333*
X0248Y00332*
X0248Y00332*
X0248Y00331*
X0248Y00331*
X02481Y00331*
X02483Y00318D02*
D01*
X02483Y00318*
X02484Y00319*
X02484Y00319*
X02484Y00319*
X02485Y0032*
X02485Y0032*
X02485Y00321*
X02485Y00321*
X02485Y00322*
X02485Y00322*
X02485Y00323*
X02485Y00323*
X02485Y00324*
X02485Y00324*
X02485Y00325*
X02485Y00326*
X02485Y00326*
X02484Y00326*
X02484Y00327*
X02484Y00327*
X02484Y00328*
X02483Y00328*
X02483Y00328*
X02473Y00318D02*
D01*
X02473Y00317*
X02473Y00317*
X02474Y00317*
X02474Y00317*
X02475Y00316*
X02475Y00316*
X02476Y00316*
X02476Y00316*
X02477Y00316*
X02477Y00316*
X02478Y00316*
X02478Y00316*
X02479Y00316*
X02479Y00316*
X0248Y00316*
X0248Y00316*
X02481Y00316*
X02481Y00316*
X02482Y00317*
X02482Y00317*
X02483Y00317*
X02483Y00318*
X02483Y00318*
X02469Y00321D02*
D01*
X02469Y00321*
X02468Y00322*
X02468Y00322*
X02468Y00322*
X02467Y00323*
X02467Y00323*
X02466Y00323*
X02466Y00323*
X02465Y00323*
X02465Y00323*
X02464Y00323*
X02464Y00323*
X02463Y00323*
X02462Y00323*
X02462Y00323*
X02461Y00323*
X02461Y00323*
X02461Y00322*
X0246Y00322*
X0246Y00322*
X02459Y00322*
X02459Y00321*
X02459Y00321*
D01*
X02458Y00321*
X02458Y0032*
X02458Y0032*
X02457Y00319*
X02457Y00319*
X02457Y00318*
X02457Y00318*
X02457Y00317*
X02456Y00317*
X02456Y00316*
X02456Y00316*
X02456Y00315*
X02456Y00315*
X02457Y00314*
X02457Y00314*
X02457Y00313*
X02457Y00313*
X02457Y00312*
X02457Y00312*
X02458Y00311*
X02458Y00311*
X02458Y00311*
X02459Y0031*
X02462Y00297D02*
D01*
X02462Y00297*
X02463Y00297*
X02463Y00298*
X02463Y00298*
X02463Y00299*
X02464Y00299*
X02464Y003*
X02464Y003*
X02464Y00301*
X02464Y00301*
X02464Y00302*
X02464Y00302*
X02464Y00303*
X02464Y00303*
X02464Y00304*
X02464Y00304*
X02463Y00305*
X02463Y00305*
X02463Y00306*
X02463Y00306*
X02462Y00307*
X02462Y00307*
X02462Y00307*
X02885Y00276D02*
D01*
X02885Y00275*
X02885Y00275*
X02885Y00275*
X02885Y00274*
X02928Y00279D02*
D01*
X02928Y00279*
X02927Y00279*
X02927Y00279*
X02927Y00279*
X02926Y00279*
X02926Y00279*
X02926Y00278*
X02925Y00278*
X02925Y00278*
X02925Y00278*
X02925Y00278*
X02924Y00277*
X02924Y00277*
X02924Y00277*
X02924Y00277*
X02923Y00276*
X02923Y00276*
X02923Y00276*
X02923Y00275*
X02923Y00275*
X02771Y00279D02*
D01*
X0277Y00279*
X0277Y00279*
X02769Y00279*
X02769Y00279*
X02769Y00279*
X02768Y00279*
X02768Y00278*
X02768Y00278*
X02768Y00278*
X02767Y00278*
X02767Y00278*
X02767Y00277*
X02767Y00277*
X02766Y00277*
X02766Y00277*
X02766Y00276*
X02766Y00276*
X02766Y00276*
X02766Y00275*
X02766Y00275*
X02692Y00795D02*
D01*
X02691Y00793*
X0269Y00792*
X02689Y0079*
X02688Y00788*
X02687Y00787*
X02686Y00785*
X02685Y00783*
X02685Y00781*
X02684Y00779*
X02684Y00777*
X02684Y00775*
X02684Y00775*
X02652Y0049D02*
D01*
X02657Y00496*
X02662Y00502*
X02666Y00508*
X0267Y00515*
X02674Y00522*
X02677Y00529*
X02679Y00536*
X02681Y00544*
X02683Y00551*
X02684Y00559*
X02684Y00567*
X02684Y00569*
X02673Y00775D02*
D01*
X02673Y00777*
X02673Y00779*
X02673Y00781*
X02672Y00782*
X02671Y00784*
X02671Y00786*
X0267Y00788*
X02669Y0079*
X02668Y00791*
X02667Y00793*
X02665Y00794*
X02665Y00795*
X02644Y00498D02*
D01*
X02649Y00503*
X02653Y00509*
X02657Y00514*
X02661Y0052*
X02664Y00527*
X02666Y00533*
X02669Y0054*
X02671Y00546*
X02672Y00553*
X02673Y0056*
X02673Y00567*
X02673Y00569*
X02563Y00383D02*
D01*
X02563Y00384*
X02564Y00385*
X02565Y00385*
X02565Y00386*
X02565Y00387*
X02566Y00388*
X02566Y00389*
X02566Y00389*
X02566Y0039*
X02566Y0039*
X02464Y00285D02*
D01*
X02464Y00284*
X02464Y00284*
X02464Y00284*
X02463Y00284*
X02463Y00283*
X02463Y00283*
X02463Y00283*
X02463Y00282*
X02463Y00282*
X02463Y00282*
X02463Y00281*
X02463Y00281*
X02463Y00281*
X02578Y0083D02*
D01*
X02576Y00828*
X02574Y00826*
X02573Y00824*
X02571Y00821*
X0257Y00819*
X02569Y00816*
X02568Y00814*
X02567Y00811*
X02567Y00808*
X02567Y00806*
X02566Y00803*
X02566Y00802*
X02807Y00775D02*
D01*
X02807Y00777*
X02807Y00779*
X02806Y00781*
X02806Y00782*
X02805Y00784*
X02805Y00786*
X02804Y00788*
X02803Y0079*
X02802Y00791*
X028Y00793*
X02799Y00794*
X02799Y00795*
X02795Y00429D02*
D01*
X02798Y00433*
X02802Y00437*
X02805Y00442*
X02808Y00446*
X02811Y00451*
X02813Y00456*
X02815Y00462*
X02816Y00467*
X02817Y00473*
X02818Y00478*
X02818Y00484*
X02818Y00485*
X02826Y00795D02*
D01*
X02825Y00793*
X02824Y00792*
X02823Y0079*
X02822Y00788*
X02821Y00787*
X0282Y00785*
X02819Y00783*
X02819Y00781*
X02818Y00779*
X02818Y00777*
X02818Y00775*
X02818Y00775*
X02787Y00437D02*
D01*
X0279Y0044*
X02793Y00444*
X02796Y00448*
X02798Y00452*
X02801Y00456*
X02802Y0046*
X02804Y00465*
X02805Y0047*
X02806Y00474*
X02807Y00479*
X02807Y00484*
X02807Y00485*
X02426Y00275D02*
D01*
X02427Y00274*
X02427Y00273*
X02428Y00271*
X02428Y0027*
X02429Y00269*
X02429Y00268*
X0243Y00267*
X02431Y00266*
X02432Y00265*
X02433Y00264*
X02434Y00264*
X02435Y00263*
X02436Y00262*
X02438Y00262*
X02439Y00261*
X0244Y00261*
X02441Y00261*
X02443Y00261*
X02444Y00261*
X02445Y00261*
X02446Y00261*
X02448Y00261*
X02449Y00261*
X0245Y00261*
X02451Y00262*
X02453Y00262*
X02454Y00263*
X02455Y00264*
X02456Y00265*
X02457Y00265*
X02458Y00266*
X02459Y00267*
X02459Y00268*
X0246Y00269*
X02461Y0027*
X02461Y00272*
X02462Y00273*
X02462Y00274*
X02463Y00275*
X02463Y00277*
X02463Y00278*
X02463Y00279*
X02463Y0028*
X02463Y00281*
X02553Y00388D02*
D01*
X02554Y00388*
X02554Y00389*
X02554Y00389*
X02554Y0039*
X02555Y0039*
X02555Y00391*
X02555Y00391*
X02555Y00392*
X02555Y00392*
X02555Y00393*
X02555Y00393*
Y00393*
X0257Y00838D02*
D01*
X02568Y00835*
X02566Y00833*
X02564Y0083*
X02562Y00827*
X0256Y00824*
X02559Y0082*
X02558Y00817*
X02557Y00814*
X02556Y0081*
X02556Y00806*
X02555Y00803*
X02555Y00802*
X02917Y0082D02*
D01*
X02917Y00822*
X02916Y00825*
X02916Y00827*
X02916Y00829*
X02915Y00832*
X02914Y00834*
X02913Y00836*
X02912Y00838*
X0291Y0084*
X02909Y00842*
X02907Y00844*
X02907Y00844*
D01*
X02905Y00846*
X02903Y00847*
X02901Y00849*
X02899Y0085*
X02897Y00851*
X02894Y00852*
X02892Y00853*
X0289Y00854*
X02887Y00854*
X02885Y00855*
X02882Y00855*
X02881Y00855*
X02781Y00887D02*
D01*
X02787Y00882*
X02793Y00877*
X02799Y00873*
X02806Y00869*
X02813Y00865*
X0282Y00862*
X02827Y00859*
X02835Y00857*
X02842Y00856*
X0285Y00855*
X02858Y00855*
X0286Y00855*
X02748Y0094D02*
D01*
X02748Y00937*
X02748Y00934*
X02749Y0093*
X0275Y00927*
X02751Y00924*
X02752Y00921*
X02754Y00918*
X02755Y00915*
X02757Y00912*
X02759Y0091*
X02761Y00907*
X02762Y00907*
X02748Y00956D02*
D01*
X02748Y00958*
X02748Y0096*
X02747Y00962*
X02747Y00964*
X02746Y00965*
X02745Y00967*
X02745Y00969*
X02744Y00971*
X02743Y00972*
X02741Y00974*
X0274Y00975*
X0274Y00976*
X02426Y00275D02*
D01*
X02426Y00275*
X02426Y00276*
X02426Y00276*
X02426Y00276*
X02426Y00277*
X02425Y00277*
X02425Y00277*
X02425Y00278*
X02425Y00278*
X02424Y00278*
X02424Y00278*
X02424Y00278*
X02424Y00279*
X02423Y00279*
X02423Y00279*
X02423Y00279*
X02422Y00279*
X02422Y00279*
X02422Y00279*
X02421Y00279*
X02608Y00861D02*
D01*
X02614Y00866*
X02618Y00872*
X02623Y00879*
X02627Y00885*
X0263Y00892*
X02633Y00899*
X02636Y00907*
X02638Y00914*
X02639Y00922*
X0264Y00929*
X02641Y00937*
X02641Y00939*
X02649Y00976D02*
D01*
X02648Y00974*
X02647Y00973*
X02645Y00971*
X02644Y00969*
X02643Y00968*
X02643Y00966*
X02642Y00964*
X02642Y00962*
X02641Y0096*
X02641Y00958*
X02641Y00956*
X02641Y00956*
X02601Y00868D02*
D01*
X02605Y00873*
X0261Y00879*
X02614Y00884*
X02617Y0089*
X0262Y00897*
X02623Y00903*
X02625Y0091*
X02627Y00916*
X02629Y00923*
X02629Y0093*
X0263Y00937*
X0263Y00939*
Y00956D02*
D01*
X0263Y00958*
X0263Y0096*
X02629Y00962*
X02629Y00964*
X02628Y00965*
X02627Y00967*
X02627Y00969*
X02626Y00971*
X02624Y00972*
X02623Y00974*
X02622Y00975*
X02622Y00976*
X02584Y00305D02*
X02587Y0032D01*
X02577Y00297D02*
D01*
X0259Y00327D02*
Y00404D01*
X02596Y00275D02*
X02596Y00275D01*
X02604Y00279D02*
X0261D01*
X026Y00278D02*
D01*
X02602Y00389D02*
D01*
Y00387D02*
Y00389D01*
Y00376D02*
Y00387D01*
X02609Y00369D02*
X02616D01*
X02607Y00354D02*
X02616D01*
X02607Y00339D02*
X02619D01*
X02604Y00324D02*
X02619D01*
X02597Y00318D02*
D01*
X02592Y00297D02*
X02597Y00318D01*
X02602Y00389D02*
Y00396D01*
X0259Y00404D02*
D01*
X02608Y00457D02*
D01*
X02923Y00398D02*
X02926Y004D01*
X0291Y00384D02*
X02923Y00398D01*
X02909Y00381D02*
X0291Y00384D01*
X02909Y00366D02*
Y00381D01*
X02916Y00359D02*
D01*
X02903Y00344D02*
X02916D01*
X02903Y00329D02*
X02915D01*
X02905Y00314D02*
X02915D01*
X02897Y00291D02*
Y00306D01*
Y00291D02*
Y00289D01*
X02926Y004D02*
X02926Y004D01*
X02928Y00404D02*
Y00834D01*
X02923Y00275D02*
D01*
X02911Y004D02*
X02911Y004D01*
X02912Y00402D02*
D01*
X02917Y00419D02*
Y0082D01*
Y00419D02*
Y00419D01*
X02915Y00852D02*
X02925Y00842D01*
X02899Y00285D02*
D01*
X02767Y00976D02*
Y00976D01*
X02759Y0094D02*
Y00956D01*
X0277Y00914D02*
X02789Y00895D01*
X0286Y00866D02*
X02881D01*
X02899Y00285D02*
X02905Y00279D01*
X02885Y00352D02*
Y00352D01*
Y00276D02*
Y00352D01*
X02748Y00282D02*
D01*
X02748Y00285D02*
D01*
X02737Y00267D02*
X02737Y00267D01*
X02748Y00285D02*
Y00289D01*
X02737Y00387D02*
X02787Y00437D01*
X02748Y00377D02*
Y0038D01*
X02748Y00355D02*
X02748Y00377D01*
X02748Y00355D02*
D01*
X02733Y00348D02*
X0274D01*
X02733Y00333D02*
X0275D01*
X02733Y00318D02*
X0275D01*
X02733Y00303D02*
X0274D01*
X02748Y00295D02*
D01*
Y00291D02*
Y00295D01*
X02748Y00289D02*
X02748Y00291D01*
X02748Y0038D02*
D01*
X02749Y00383D02*
X02795Y00429D01*
X02633Y00472D02*
X02652Y0049D01*
X02633Y00472D02*
D01*
X02526Y0036D02*
X02543Y00378D01*
X02515Y0036D02*
D01*
D01*
X02504Y0035D02*
D01*
X02491Y00341D02*
X02494Y00339D01*
X02481Y00331D02*
X02483Y00328D01*
X02469Y00321D02*
X02473Y00318D01*
X02459Y0031D02*
X02462Y00307D01*
X0246Y00295D02*
X02462Y00297D01*
X02543Y00378D02*
X02553Y00388D01*
X02444Y00279D02*
X0246Y00295D01*
X02807Y00485D02*
Y00775D01*
X02818Y00485D02*
Y00775D01*
X02673Y00569D02*
Y00775D01*
X02684Y00569D02*
Y00775D01*
X02555Y00393D02*
Y00802D01*
X02692Y00795D02*
Y00795D01*
X02665Y00795D02*
Y00795D01*
X02625Y0048D02*
X02644Y00498D01*
X02464Y00285D02*
X02563Y00383D01*
X02566Y0039D02*
Y00802D01*
X02771Y00279D02*
X02779D01*
X02799Y00795D02*
Y00795D01*
X02826Y00795D02*
Y00795D01*
X02578Y0083D02*
X02608Y00861D01*
X02463Y00281D02*
D01*
X02578Y0083D02*
D01*
X02555Y00393D02*
D01*
X02928Y00279D02*
X02937D01*
X02881Y00855D02*
D01*
X0286D02*
X02881D01*
X02748Y0094D02*
Y00956D01*
X0274Y00976D02*
Y00976D01*
X02762Y00907D02*
X02781Y00887D01*
X02421Y00279D02*
D01*
X02413D02*
X02421D01*
X02641Y00939D02*
Y00956D01*
X02649Y00976D02*
Y00976D01*
Y00976D02*
D01*
X0257Y00838D02*
X02601Y00868D01*
X0263Y00939D02*
Y00956D01*
X02622Y00976D02*
Y00976D01*
G54D153*
X01909Y04284D02*
X01941Y04316D01*
X01496Y04204D02*
X01576Y04284D01*
X01909*
X02152Y04316D02*
X02186Y04283D01*
X01941Y04316D02*
X02152D01*
X02186Y04283D02*
X0257D01*
X01413Y04204D02*
X01496D01*
X01362Y04256D02*
X01413Y04204D01*
X01294Y04256D02*
X01362D01*
X01849Y03701D02*
X06294D01*
G54D161*
X0418Y02595D03*
X04298D03*
G54D168*
X02043Y04157D03*
G54D171*
X02494Y02661D03*
X0261Y00279D03*
X02578D03*
X02748Y00282D03*
X02905Y00279D03*
X02692Y00795D03*
X02665D03*
X02779Y00279D03*
X02937D03*
X0274Y00976D03*
X02767D03*
X02413Y00279D03*
X02444D03*
X02649Y00976D03*
X02622D03*
X02799Y00795D03*
X02826D03*
X0233Y02215D03*
X01798Y01304D03*
X03379Y01386D03*
X02821Y02601D03*
X03554Y01891D03*
X02841Y02263D03*
X02394Y0272D03*
X01567Y01285D03*
X02494Y02696D03*
X03404Y01363D03*
X02803Y02307D03*
X01822Y01674D03*
X01893Y01693D03*
X02409Y02314D03*
X02958Y02621D03*
X03804Y0184D03*
X01879Y01811D03*
X03407Y01411D03*
X02575Y02412D03*
X02499Y02236D03*
X02948Y02456D03*
X03719Y01766D03*
X02645Y02274D03*
X03379Y01336D03*
X01393Y01816D03*
X04794Y02808D03*
X03183Y03135D03*
X03277Y02963D03*
X03197Y0297D03*
X03188Y03187D03*
X0323Y03235D03*
X03275Y03141D03*
X03056Y01811D03*
X02434Y03546D03*
X02591Y03186D03*
X0259Y03288D03*
X00996Y02256D03*
X02004Y01336D03*
X02028Y01361D03*
X02549Y01755D03*
X02418Y03118D03*
X02414Y03199D03*
X02462Y03172D03*
X01408Y0398D03*
X00996Y01187D03*
X00988Y01717D03*
X02353Y04017D03*
X04039Y02406D03*
X04134Y01651D03*
X03994Y01551D03*
X04134Y01751D03*
X04151Y01623D03*
X03969Y01552D03*
X03944Y01816D03*
X04179Y01601D03*
X04034Y01546D03*
X04064Y01796D03*
Y01511D03*
X03263Y03303D03*
X01569Y04171D03*
X05267Y04088D03*
X05577Y02214D03*
X02694Y01481D03*
X02384Y01941D03*
X06334Y03266D03*
X03744Y03261D03*
X05634Y02236D03*
X02626Y0177D03*
X06304Y03121D03*
X03939D03*
X02604Y01734D03*
X02299Y01916D03*
X02579Y0179D03*
X02259Y03261D03*
X03374Y03273D03*
X06282Y03226D03*
X03806Y03235D03*
X0337Y02888D03*
X0257Y04283D03*
X01459Y03147D03*
X0144Y03557D03*
X01903Y04018D03*
X03623Y02587D03*
X03542Y03319D03*
X03653Y03293D03*
X03394Y03447D03*
X03436Y03457D03*
X02799Y03616D03*
X03589Y01711D03*
X02478Y00937D03*
X02206Y01298D03*
X02205Y032D03*
X02502Y01316D03*
X02525Y02463D03*
X03342Y02263D03*
X03498Y02341D03*
X02429Y02621D03*
X01004Y00906D03*
X02446Y01437D03*
X01008Y0143D03*
X02409Y01967D03*
X01009Y01956D03*
X0102Y02481D03*
X02643Y01616D03*
X02666Y0164D03*
X01884Y03601D03*
X01754Y03661D03*
X03424Y03636D03*
X01549Y03621D03*
X03239Y03596D03*
X01574D03*
X02083Y01411D03*
X02059Y01386D03*
X01294Y04256D03*
X02234Y03506D03*
X03529Y03481D03*
X02679Y03661D03*
X02993Y03751D03*
X03699D03*
X03014Y03831D03*
X03699Y03836D03*
X02894Y01561D03*
X02919Y01536D03*
X02274Y01506D03*
X02719Y01591D03*
X03724Y01675D03*
X06309Y03199D03*
X06339Y03151D03*
X04754Y04115D03*
X01779Y04156D03*
X03504Y04086D03*
X03854Y03151D03*
X03829Y03176D03*
X03799Y03201D03*
X06439Y03191D03*
X06354Y03331D03*
X06444Y03291D03*
X03302Y03344D03*
X06409Y03371D03*
X06447Y03396D03*
X06479Y03426D03*
X06509Y03456D03*
X03469D03*
X01849Y03701D03*
X06294D03*
M02*